# T6G (Grand Teton) — schematic netlist excerpt (pin names and nets, part order shuffled) for the footprints in the layout excerpt that follows; sources: Cadence DE-HDL packaged netlist, KiCad conversion of 04192023_DAF0TMB3IC0_F0TG_MB_C_brd_V02_OCP.brd

C2615  Q_CAP  22UF 4V 20% X6S  pkg C0402  page 70 : A = PVDD11_S3_P0 ; B = GND
C2438  Q_CAP  22UF 4V 20% X6S  pkg C0402  page 74 : A = PVDDCR_SOC_P1 ; B = GND

(kicad_pcb
	(version 20260206)
	(generator "pcbnew")
	(generator_version "10.0")
	(general
		(thickness 1.6)
		(legacy_teardrops no)
	)
	(paper "A4")
	(title_block
		(title "04192023_DAF0TMB3IC0_F0TG_MB_C_brd_V02_OCP.brd")
		(comment 1 "Grand Teton / footprints 6369-6370 of 8354")
	)
	(layers
		(0 "F.Cu" signal "TOP")
		(4 "In1.Cu" signal "GND")
		(6 "In2.Cu" signal "IN1")
		(8 "In3.Cu" signal "GND1")
		(10 "In4.Cu" signal "IN2")
		(12 "In5.Cu" signal "GND2")
		(14 "In6.Cu" signal "IN3")
		(16 "In7.Cu" signal "GND3")
		(18 "In8.Cu" signal "VCC")
		(20 "In9.Cu" signal "VCC1")
		(22 "In10.Cu" signal "GND4")
		(24 "In11.Cu" signal "IN4")
		(26 "In12.Cu" signal "GND5")
		(28 "In13.Cu" signal "IN5")
		(30 "In14.Cu" signal "GND6")
		(32 "In15.Cu" signal "IN6")
		(34 "In16.Cu" signal "GND7")
		(2 "B.Cu" signal "BOTTOM")
		(9 "F.Adhes" user "F.Adhesive")
		(11 "B.Adhes" user "B.Adhesive")
		(13 "F.Paste" user "Package Geometry/Pastemask Top")
		(15 "B.Paste" user "Package Geometry/Pastemask Bottom")
		(5 "F.SilkS" user "Ref Des/Silkscreen Top")
		(7 "B.SilkS" user "Ref Des/Silkscreen Bottom")
		(1 "F.Mask" user "Board Geometry/Soldermask Top")
		(3 "B.Mask" user "Board Geometry/Soldermask Bottom")
		(17 "Dwgs.User" user "User.Drawings")
		(19 "Cmts.User" user "User.Comments")
		(21 "Eco1.User" user "User.Eco1")
		(23 "Eco2.User" user "User.Eco2")
		(25 "Edge.Cuts" user "Board Geometry/Outline")
		(27 "Margin" user)
		(31 "F.CrtYd" user "Package Geometry/Place Bound Top")
		(29 "B.CrtYd" user "Package Geometry/Place Bound Bottom")
		(35 "F.Fab" user "Ref Des/Assembly Top")
		(33 "B.Fab" user "Ref Des/Assembly Bottom")
	)
	(footprint ""
		(layer "B.Cu")
		(at 355.617272 -261.747762 90)
		(property "Reference" "C2615"
			(at 0 0 90)
			(layer "B.SilkS")
			(hide yes)
			(effects
				(font
					(size 1.27 1.27)
				)
				(justify mirror)
			)
		)
		(property "Value" ""
			(at 0 0 90)
			(layer "B.Fab")
			(effects
				(font
					(size 1.27 1.27)
				)
				(justify mirror)
			)
		)
		(duplicate_pad_numbers_are_jumpers no)
		(fp_line
			(start 0.7874 -0.4064)
			(end -0.7874 -0.4064)
			(stroke
				(width 0.1524)
				(type default)
			)
			(layer "B.SilkS")
		)
		(fp_line
			(start -0.7874 -0.4064)
			(end -0.7874 0.4064)
			(stroke
				(width 0.1524)
				(type default)
			)
			(layer "B.SilkS")
		)
		(fp_line
			(start 0.7874 0.4064)
			(end 0.7874 -0.4064)
			(stroke
				(width 0.1524)
				(type default)
			)
			(layer "B.SilkS")
		)
		(fp_line
			(start -0.7874 0.4064)
			(end 0.7874 0.4064)
			(stroke
				(width 0.1524)
				(type default)
			)
			(layer "B.SilkS")
		)
		(fp_line
			(start 0.67945 -0.305054)
			(end 0.12065 -0.305054)
			(stroke
				(width 0.1)
				(type default)
			)
			(layer "B.Fab")
		)
		(fp_line
			(start 0.12065 -0.305054)
			(end 0.12065 -0.2794)
			(stroke
				(width 0.1)
				(type default)
			)
			(layer "B.Fab")
		)
		(fp_line
			(start -0.12065 -0.3048)
			(end -0.67945 -0.3048)
			(stroke
				(width 0.1)
				(type default)
			)
			(layer "B.Fab")
		)
		(fp_line
			(start -0.67945 -0.3048)
			(end -0.67945 0.3048)
			(stroke
				(width 0.1)
				(type default)
			)
			(layer "B.Fab")
		)
		(fp_line
			(start 0.12065 -0.2794)
			(end -0.12065 -0.2794)
			(stroke
				(width 0.1)
				(type default)
			)
			(layer "B.Fab")
		)
		(fp_line
			(start -0.12065 -0.2794)
			(end -0.12065 -0.3048)
			(stroke
				(width 0.1)
				(type default)
			)
			(layer "B.Fab")
		)
		(fp_line
			(start 0.12065 0.2794)
			(end 0.12065 0.3048)
			(stroke
				(width 0.1)
				(type default)
			)
			(layer "B.Fab")
		)
		(fp_line
			(start -0.120396 0.2794)
			(end 0.12065 0.2794)
			(stroke
				(width 0.1)
				(type default)
			)
			(layer "B.Fab")
		)
		(fp_line
			(start 0.67945 0.3048)
			(end 0.67945 -0.305054)
			(stroke
				(width 0.1)
				(type default)
			)
			(layer "B.Fab")
		)
		(fp_line
			(start 0.12065 0.3048)
			(end 0.67945 0.3048)
			(stroke
				(width 0.1)
				(type default)
			)
			(layer "B.Fab")
		)
		(fp_line
			(start -0.120396 0.3048)
			(end -0.120396 0.2794)
			(stroke
				(width 0.1)
				(type default)
			)
			(layer "B.Fab")
		)
		(fp_line
			(start -0.67945 0.3048)
			(end -0.120396 0.3048)
			(stroke
				(width 0.1)
				(type default)
			)
			(layer "B.Fab")
		)
		(pad "1" smd circle
			(at 0.40005 0 270)
			(size 0 0)
			(layers "B.Cu" "B.Mask" "B.Paste")
			(net "PVDD11_S3_P0")
		)
		(pad "2" smd circle
			(at -0.40005 0 270)
			(size 0 0)
			(layers "B.Cu" "B.Mask" "B.Paste")
			(net "GND")
		)
	)
	(footprint ""
		(layer "B.Cu")
		(at 108.117386 -251.781564)
		(property "Reference" "C2438"
			(at 0 0 0)
			(layer "B.SilkS")
			(hide yes)
			(effects
				(font
					(size 1.27 1.27)
				)
				(justify mirror)
			)
		)
		(property "Value" ""
			(at 0 0 0)
			(layer "B.Fab")
			(effects
				(font
					(size 1.27 1.27)
				)
				(justify mirror)
			)
		)
		(duplicate_pad_numbers_are_jumpers no)
		(fp_line
			(start -0.7874 -0.4064)
			(end -0.7874 0.4064)
			(stroke
				(width 0.1524)
				(type default)
			)
			(layer "B.SilkS")
		)
		(fp_line
			(start -0.7874 0.4064)
			(end 0.7874 0.4064)
			(stroke
				(width 0.1524)
				(type default)
			)
			(layer "B.SilkS")
		)
		(fp_line
			(start 0.7874 -0.4064)
			(end -0.7874 -0.4064)
			(stroke
				(width 0.1524)
				(type default)
			)
			(layer "B.SilkS")
		)
		(fp_line
			(start 0.7874 0.4064)
			(end 0.7874 -0.4064)
			(stroke
				(width 0.1524)
				(type default)
			)
			(layer "B.SilkS")
		)
		(fp_line
			(start -0.67945 -0.3048)
			(end -0.67945 0.3048)
			(stroke
				(width 0.1)
				(type default)
			)
			(layer "B.Fab")
		)
		(fp_line
			(start -0.67945 0.3048)
			(end -0.120396 0.3048)
			(stroke
				(width 0.1)
				(type default)
			)
			(layer "B.Fab")
		)
		(fp_line
			(start -0.12065 -0.3048)
			(end -0.67945 -0.3048)
			(stroke
				(width 0.1)
				(type default)
			)
			(layer "B.Fab")
		)
		(fp_line
			(start -0.12065 -0.2794)
			(end -0.12065 -0.3048)
			(stroke
				(width 0.1)
				(type default)
			)
			(layer "B.Fab")
		)
		(fp_line
			(start -0.120396 0.2794)
			(end 0.12065 0.2794)
			(stroke
				(width 0.1)
				(type default)
			)
			(layer "B.Fab")
		)
		(fp_line
			(start -0.120396 0.3048)
			(end -0.120396 0.2794)
			(stroke
				(width 0.1)
				(type default)
			)
			(layer "B.Fab")
		)
		(fp_line
			(start 0.12065 -0.305054)
			(end 0.12065 -0.2794)
			(stroke
				(width 0.1)
				(type default)
			)
			(layer "B.Fab")
		)
		(fp_line
			(start 0.12065 -0.2794)
			(end -0.12065 -0.2794)
			(stroke
				(width 0.1)
				(type default)
			)
			(layer "B.Fab")
		)
		(fp_line
			(start 0.12065 0.2794)
			(end 0.12065 0.3048)
			(stroke
				(width 0.1)
				(type default)
			)
			(layer "B.Fab")
		)
		(fp_line
			(start 0.12065 0.3048)
			(end 0.67945 0.3048)
			(stroke
				(width 0.1)
				(type default)
			)
			(layer "B.Fab")
		)
		(fp_line
			(start 0.67945 -0.305054)
			(end 0.12065 -0.305054)
			(stroke
				(width 0.1)
				(type default)
			)
			(layer "B.Fab")
		)
		(fp_line
			(start 0.67945 0.3048)
			(end 0.67945 -0.305054)
			(stroke
				(width 0.1)
				(type default)
			)
			(layer "B.Fab")
		)
		(pad "1" smd circle
			(at 0.40005 0 180)
			(size 0 0)
			(layers "B.Cu" "B.Mask" "B.Paste")
			(net "PVDDCR_SOC_P1")
		)
		(pad "2" smd circle
			(at -0.40005 0 180)
			(size 0 0)
			(layers "B.Cu" "B.Mask" "B.Paste")
			(net "GND")
		)
	)
)
